(kicad_pcb
	(version 20260206)
	(generator "pcbnew")
	(generator_version "10.0")
	(general
		(thickness 1.6)
		(legacy_teardrops no)
	)
	(paper "A4")
	(title_block
		(title "v1-pdb — T6M_PDB_D_0927_0900.brd")
		(comment 1 "Open CloudServer (Microsoft) / footprints 217-224 of 321")
	)
	(layers
		(0 "F.Cu" signal "TOP")
		(4 "In1.Cu" signal "GND")
		(6 "In2.Cu" signal "IN1")
		(8 "In3.Cu" signal "VCC")
		(10 "In4.Cu" signal "VCC1")
		(12 "In5.Cu" signal "IN2")
		(14 "In6.Cu" signal "GND1")
		(2 "B.Cu" signal "BOTTOM")
		(9 "F.Adhes" user "F.Adhesive")
		(11 "B.Adhes" user "B.Adhesive")
		(13 "F.Paste" user "Package Geometry/Pastemask Top")
		(15 "B.Paste" user "Package Geometry/Pastemask Bottom")
		(5 "F.SilkS" user "Ref Des/Silkscreen Top")
		(7 "B.SilkS" user "Ref Des/Silkscreen Bottom")
		(1 "F.Mask" user "Board Geometry/Soldermask Top")
		(3 "B.Mask" user "Board Geometry/Soldermask Bottom")
		(17 "Dwgs.User" user "User.Drawings")
		(19 "Cmts.User" user "User.Comments")
		(21 "Eco1.User" user "User.Eco1")
		(23 "Eco2.User" user "User.Eco2")
		(25 "Edge.Cuts" user "Board Geometry/Outline")
		(27 "Margin" user)
		(31 "F.CrtYd" user "Package Geometry/Place Bound Top")
		(29 "B.CrtYd" user "Package Geometry/Place Bound Bottom")
		(35 "F.Fab" user "Ref Des/Assembly Top")
		(33 "B.Fab" user "Ref Des/Assembly Bottom")
	)
	(footprint ""
		(layer "F.Cu")
		(at 71.392796 -87.145368 90)
		(property "Reference" "C21"
			(at -4.3307 -0.164846 90)
			(unlocked yes)
			(layer "F.SilkS")
			(effects
				(font
					(size 0.7874 0.5842)
					(thickness 0.1524)
				)
				(justify left)
			)
		)
		(property "Value" ""
			(at 0 0 90)
			(layer "F.Fab")
			(effects
				(font
					(size 1.27 1.27)
				)
			)
		)
		(duplicate_pad_numbers_are_jumpers no)
		(fp_line
			(start 0.7874 -0.4064)
			(end 0.7874 0.4064)
			(stroke
				(width 0.1524)
				(type default)
			)
			(layer "F.SilkS")
		)
		(fp_line
			(start -0.7874 -0.4064)
			(end 0.7874 -0.4064)
			(stroke
				(width 0.1524)
				(type default)
			)
			(layer "F.SilkS")
		)
		(fp_line
			(start 0 0.381)
			(end 0 -0.381)
			(stroke
				(width 0.1524)
				(type default)
			)
			(layer "F.SilkS")
		)
		(fp_line
			(start 0.7874 0.4064)
			(end -0.7874 0.4064)
			(stroke
				(width 0.1524)
				(type default)
			)
			(layer "F.SilkS")
		)
		(fp_line
			(start -0.7874 0.4064)
			(end -0.7874 -0.4064)
			(stroke
				(width 0.1524)
				(type default)
			)
			(layer "F.SilkS")
		)
		(fp_poly
			(pts
				(xy -0.5334 0.254) (xy -0.635 0.254) (xy -0.635 0.2286) (xy -0.635 -0.254) (xy -0.5334 -0.254) (xy -0.5334 -0.2794)
				(xy 0.5334 -0.2794) (xy 0.5334 -0.254) (xy 0.635 -0.254) (xy 0.635 0.254) (xy 0.5334 0.254) (xy 0.5334 0.2794)
				(xy -0.508 0.2794) (xy -0.5334 0.2794)
			)
			(stroke
				(width 0)
				(type default)
			)
			(fill no)
			(layer "F.CrtYd")
		)
		(pad "1" smd rect
			(at 0.40005 0 90)
			(size 0.4572 0.508)
			(layers "F.Cu" "F.Mask" "F.Paste")
			(net "P12V")
		)
		(pad "2" smd rect
			(at -0.40005 0 90)
			(size 0.4572 0.508)
			(layers "F.Cu" "F.Mask" "F.Paste")
			(net "GND")
		)
	)
	(footprint ""
		(layer "F.Cu")
		(at 50.350928 -306.383182 180)
		(property "Reference" "CE14"
			(at 8.029448 2.021078 0)
			(unlocked yes)
			(layer "F.SilkS")
			(effects
				(font
					(size 0.7874 0.5842)
					(thickness 0.1524)
				)
				(justify left)
			)
		)
		(property "Value" ""
			(at 0 0 180)
			(layer "F.Fab")
			(effects
				(font
					(size 1.27 1.27)
				)
			)
		)
		(duplicate_pad_numbers_are_jumpers no)
		(fp_line
			(start 0 -4.2672)
			(end 0 4.2672)
			(stroke
				(width 0.1524)
				(type default)
			)
			(layer "F.SilkS")
		)
		(fp_circle
			(center 0 0)
			(end -4.2672 0)
			(stroke
				(width 0.1524)
				(type default)
			)
			(fill no)
			(layer "F.SilkS")
		)
		(fp_poly
			(pts
				(arc
					(start 0 -4.2672)
					(mid 4.2672 0)
					(end 0 4.2672)
				)
			)
			(stroke
				(width 0)
				(type default)
			)
			(fill yes)
			(layer "F.SilkS")
		)
		(fp_poly
			(pts
				(xy -2.5146 -0.762) (xy -0.9906 -0.762) (xy -0.9906 0.762) (xy -2.5146 0.762)
			)
			(stroke
				(width 0)
				(type default)
			)
			(fill no)
			(layer "B.CrtYd")
		)
		(fp_poly
			(pts
				(arc
					(start 1.7526 0.762)
					(mid 2.291415 -0.538815)
					(end 0.9906 0)
				)
				(arc
					(start 0.9906 0.0254)
					(mid 1.206345 0.546255)
					(end 1.7272 0.762)
				)
			)
			(stroke
				(width 0)
				(type default)
			)
			(fill no)
			(layer "B.CrtYd")
		)
		(fp_poly
			(pts
				(arc
					(start -4.2672 0)
					(mid 4.2672 0)
					(end -4.2672 0)
				)
			)
			(stroke
				(width 0)
				(type default)
			)
			(fill no)
			(layer "F.CrtYd")
		)
		(fp_circle
			(center 0 0)
			(end -4.2672 0)
			(stroke
				(width 0.1)
				(type default)
			)
			(fill no)
			(layer "F.Fab")
		)
		(fp_text user "+"
			(at -5.6642 0.15367 180)
			(unlocked yes)
			(layer "F.SilkS")
			(effects
				(font
					(size 0.7874 0.5842)
					(thickness 0.1524)
				)
				(justify left)
			)
		)
		(fp_text user "+"
			(at -5.6642 -0.34925 180)
			(unlocked yes)
			(layer "F.Fab")
			(effects
				(font
					(size 1.905 1.4224)
					(thickness 0.000001)
				)
				(justify left)
			)
		)
		(pad "1" thru_hole rect
			(at -1.75006 0 180)
			(size 1.397 1.397)
			(drill 0.9144)
			(layers "*.Cu" "*.Mask")
			(remove_unused_layers no)
			(net "P12V")
			(clearance 0.0127)
			(thermal_gap 0.0127)
			(padstack
				(mode front_inner_back)
				(layer "Inner"
					(shape circle)
					(size 1.397 1.397)
					(clearance 0.0127)
				)
				(layer "B.Cu"
					(shape rect)
					(size 1.397 1.397)
					(clearance 0.0127)
				)
			)
		)
		(pad "2" thru_hole circle
			(at 1.75006 0 180)
			(size 1.397 1.397)
			(drill 0.9144)
			(layers "*.Cu" "*.Mask")
			(remove_unused_layers no)
			(net "GND")
			(clearance 0.0127)
			(thermal_gap 0.0127)
		)
	)
	(footprint ""
		(layer "F.Cu")
		(at 68.457064 -131.443476 90)
		(property "Reference" "C28"
			(at -3.793744 -0.09398 90)
			(unlocked yes)
			(layer "F.SilkS")
			(effects
				(font
					(size 0.7874 0.5842)
					(thickness 0.1524)
				)
				(justify left)
			)
		)
		(property "Value" ""
			(at 0 0 90)
			(layer "F.Fab")
			(effects
				(font
					(size 1.27 1.27)
				)
			)
		)
		(duplicate_pad_numbers_are_jumpers no)
		(fp_line
			(start 0.7874 -0.4064)
			(end 0.7874 0.4064)
			(stroke
				(width 0.1524)
				(type default)
			)
			(layer "F.SilkS")
		)
		(fp_line
			(start -0.7874 -0.4064)
			(end 0.7874 -0.4064)
			(stroke
				(width 0.1524)
				(type default)
			)
			(layer "F.SilkS")
		)
		(fp_line
			(start 0 0.381)
			(end 0 -0.381)
			(stroke
				(width 0.1524)
				(type default)
			)
			(layer "F.SilkS")
		)
		(fp_line
			(start 0.7874 0.4064)
			(end -0.7874 0.4064)
			(stroke
				(width 0.1524)
				(type default)
			)
			(layer "F.SilkS")
		)
		(fp_line
			(start -0.7874 0.4064)
			(end -0.7874 -0.4064)
			(stroke
				(width 0.1524)
				(type default)
			)
			(layer "F.SilkS")
		)
		(fp_poly
			(pts
				(xy -0.5334 0.254) (xy -0.635 0.254) (xy -0.635 0.2286) (xy -0.635 -0.254) (xy -0.5334 -0.254) (xy -0.5334 -0.2794)
				(xy 0.5334 -0.2794) (xy 0.5334 -0.254) (xy 0.635 -0.254) (xy 0.635 0.254) (xy 0.5334 0.254) (xy 0.5334 0.2794)
				(xy -0.508 0.2794) (xy -0.5334 0.2794)
			)
			(stroke
				(width 0)
				(type default)
			)
			(fill no)
			(layer "F.CrtYd")
		)
		(pad "1" smd rect
			(at 0.40005 0 90)
			(size 0.4572 0.508)
			(layers "F.Cu" "F.Mask" "F.Paste")
			(net "P12V")
		)
		(pad "2" smd rect
			(at -0.40005 0 90)
			(size 0.4572 0.508)
			(layers "F.Cu" "F.Mask" "F.Paste")
			(net "GND")
		)
	)
	(footprint ""
		(layer "F.Cu")
		(at 27.28468 -4.025138)
		(property "Reference" "R65"
			(at -1.676146 2.569972 0)
			(unlocked yes)
			(layer "F.SilkS")
			(effects
				(font
					(size 0.7874 0.5842)
					(thickness 0.1524)
				)
				(justify left)
			)
		)
		(property "Value" ""
			(at 0 0 0)
			(layer "F.Fab")
			(effects
				(font
					(size 1.27 1.27)
				)
			)
		)
		(duplicate_pad_numbers_are_jumpers no)
		(fp_line
			(start -0.7874 -0.4064)
			(end 0.7874 -0.4064)
			(stroke
				(width 0.1524)
				(type default)
			)
			(layer "F.SilkS")
		)
		(fp_line
			(start -0.7874 0.4064)
			(end -0.7874 -0.4064)
			(stroke
				(width 0.1524)
				(type default)
			)
			(layer "F.SilkS")
		)
		(fp_line
			(start 0.7874 -0.4064)
			(end 0.7874 0.4064)
			(stroke
				(width 0.1524)
				(type default)
			)
			(layer "F.SilkS")
		)
		(fp_line
			(start 0.7874 0.4064)
			(end -0.7874 0.4064)
			(stroke
				(width 0.1524)
				(type default)
			)
			(layer "F.SilkS")
		)
		(fp_poly
			(pts
				(xy -0.508 0.2794) (xy -0.508 0.2286) (xy -0.635 0.2286) (xy -0.635 -0.254) (xy -0.5334 -0.254)
				(xy -0.5334 -0.2794) (xy 0.5334 -0.2794) (xy 0.5334 -0.254) (xy 0.635 -0.254) (xy 0.635 0.254) (xy 0.5334 0.254)
				(xy 0.5334 0.2794)
			)
			(stroke
				(width 0)
				(type default)
			)
			(fill no)
			(layer "F.CrtYd")
		)
		(pad "1" smd rect
			(at 0.40005 0)
			(size 0.4572 0.508)
			(layers "F.Cu" "F.Mask" "F.Paste")
			(net "PSU1_RESET")
		)
		(pad "2" smd rect
			(at -0.40005 0)
			(size 0.4572 0.508)
			(layers "F.Cu" "F.Mask" "F.Paste")
			(net "GND")
		)
	)
	(footprint ""
		(layer "F.Cu")
		(at 2.439924 -159.325056 90)
		(property "Reference" "J30"
			(at -1.364488 4.743704 90)
			(unlocked yes)
			(layer "F.SilkS")
			(effects
				(font
					(size 0.7874 0.5842)
					(thickness 0.1524)
				)
				(justify left)
			)
		)
		(property "Value" ""
			(at 0 0 90)
			(layer "F.Fab")
			(effects
				(font
					(size 1.27 1.27)
				)
			)
		)
		(duplicate_pad_numbers_are_jumpers no)
		(fp_line
			(start 1.849882 -1.999996)
			(end -3.02006 -1.999996)
			(stroke
				(width 0.1524)
				(type default)
			)
			(layer "F.SilkS")
		)
		(fp_line
			(start -3.02006 -1.999996)
			(end -3.02006 3.999992)
			(stroke
				(width 0.1524)
				(type default)
			)
			(layer "F.SilkS")
		)
		(fp_line
			(start 1.35001 -1.500124)
			(end -2.519934 -1.500124)
			(stroke
				(width 0.1524)
				(type default)
			)
			(layer "F.SilkS")
		)
		(fp_line
			(start -2.519934 -1.500124)
			(end -2.519934 3.50012)
			(stroke
				(width 0.1524)
				(type default)
			)
			(layer "F.SilkS")
		)
		(fp_line
			(start 1.849882 0.500126)
			(end 1.35001 0.500126)
			(stroke
				(width 0.1524)
				(type default)
			)
			(layer "F.SilkS")
		)
		(fp_line
			(start 1.35001 0.500126)
			(end 1.35001 -1.500124)
			(stroke
				(width 0.1524)
				(type default)
			)
			(layer "F.SilkS")
		)
		(fp_line
			(start 1.35001 1.500124)
			(end 1.849882 1.500124)
			(stroke
				(width 0.1524)
				(type default)
			)
			(layer "F.SilkS")
		)
		(fp_line
			(start 1.35001 3.50012)
			(end 1.35001 1.500124)
			(stroke
				(width 0.1524)
				(type default)
			)
			(layer "F.SilkS")
		)
		(fp_line
			(start -2.519934 3.50012)
			(end 1.35001 3.50012)
			(stroke
				(width 0.1524)
				(type default)
			)
			(layer "F.SilkS")
		)
		(fp_line
			(start 1.849882 3.999992)
			(end 1.849882 -1.999996)
			(stroke
				(width 0.1524)
				(type default)
			)
			(layer "F.SilkS")
		)
		(fp_line
			(start -3.02006 3.999992)
			(end 1.849882 3.999992)
			(stroke
				(width 0.1524)
				(type default)
			)
			(layer "F.SilkS")
		)
		(fp_poly
			(pts
				(xy 2.01041 0) (xy 3.06959 -0.52959) (xy 3.06959 0.52959)
			)
			(stroke
				(width 0)
				(type default)
			)
			(fill yes)
			(layer "F.SilkS")
		)
		(fp_poly
			(pts
				(xy -0.8382 2.8194) (xy 0.8382 2.8194) (xy 0.8382 -0.8382) (xy -0.8382 -0.8382)
			)
			(stroke
				(width 0)
				(type default)
			)
			(fill no)
			(layer "B.CrtYd")
		)
		(fp_poly
			(pts
				(xy -3.02006 3.999992) (xy 1.849882 3.999992) (xy 1.849882 -1.999996) (xy -3.02006 -1.999996)
			)
			(stroke
				(width 0)
				(type default)
			)
			(fill no)
			(layer "F.CrtYd")
		)
		(fp_line
			(start 1.849882 -1.999996)
			(end -3.02006 -1.999996)
			(stroke
				(width 0.1)
				(type default)
			)
			(layer "F.Fab")
		)
		(fp_line
			(start -3.02006 -1.999996)
			(end -3.02006 3.999992)
			(stroke
				(width 0.1)
				(type default)
			)
			(layer "F.Fab")
		)
		(fp_line
			(start 1.849882 3.999992)
			(end 1.849882 -1.999996)
			(stroke
				(width 0.1)
				(type default)
			)
			(layer "F.Fab")
		)
		(fp_line
			(start -3.02006 3.999992)
			(end 1.849882 3.999992)
			(stroke
				(width 0.1)
				(type default)
			)
			(layer "F.Fab")
		)
		(fp_poly
			(pts
				(xy 2.01041 0) (xy 3.06959 -0.52959) (xy 3.06959 0.52959)
			)
			(stroke
				(width 0)
				(type default)
			)
			(fill yes)
			(layer "F.Fab")
		)
		(fp_text user "2"
			(at 2.5527 2.16535 90)
			(unlocked yes)
			(layer "F.SilkS")
			(effects
				(font
					(size 0.7874 0.5842)
					(thickness 0.1524)
				)
			)
		)
		(fp_text user "1"
			(at 1.2192 0.00127 90)
			(unlocked yes)
			(layer "B.SilkS")
			(effects
				(font
					(size 0.7874 0.5842)
					(thickness 0.1524)
				)
				(justify mirror)
			)
		)
		(fp_text user "2"
			(at 1.2192 2.001266 90)
			(unlocked yes)
			(layer "B.SilkS")
			(effects
				(font
					(size 0.7874 0.5842)
					(thickness 0.1524)
				)
				(justify mirror)
			)
		)
		(fp_text user "1"
			(at 1.2192 0.00127 90)
			(unlocked yes)
			(layer "B.Fab")
			(effects
				(font
					(size 0.7874 0.5842)
					(thickness 0.1524)
				)
				(justify mirror)
			)
		)
		(fp_text user "2"
			(at 1.2192 2.001266 90)
			(unlocked yes)
			(layer "B.Fab")
			(effects
				(font
					(size 0.7874 0.5842)
					(thickness 0.1524)
				)
				(justify mirror)
			)
		)
		(fp_text user "2"
			(at 2.5527 2.16535 90)
			(unlocked yes)
			(layer "F.Fab")
			(effects
				(font
					(size 0.7874 0.5842)
					(thickness 0.1524)
				)
			)
		)
		(pad "1" thru_hole rect
			(at 0 0 90)
			(size 1.524 1.524)
			(drill 1.016)
			(layers "*.Cu" "*.Mask")
			(remove_unused_layers no)
			(net "POWER_SW3_PWR_CTR_12V")
			(clearance 0)
			(padstack
				(mode front_inner_back)
				(layer "Inner"
					(shape circle)
					(size 1.524 1.524)
					(clearance 0)
				)
				(layer "B.Cu"
					(shape rect)
					(size 1.524 1.524)
					(clearance 0)
				)
			)
		)
		(pad "2" thru_hole circle
			(at 0 1.999996 90)
			(size 1.524 1.524)
			(drill 1.016)
			(layers "*.Cu" "*.Mask")
			(remove_unused_layers no)
			(net "GND")
			(clearance 0)
		)
	)
	(footprint ""
		(layer "F.Cu")
		(at 73.199752 -282.156154 -90)
		(property "Reference" "C44"
			(at 0.870204 -4.091432 90)
			(unlocked yes)
			(layer "F.SilkS")
			(effects
				(font
					(size 0.7874 0.5842)
					(thickness 0.1524)
				)
				(justify left)
			)
		)
		(property "Value" ""
			(at 0 0 270)
			(layer "F.Fab")
			(effects
				(font
					(size 1.27 1.27)
				)
			)
		)
		(duplicate_pad_numbers_are_jumpers no)
		(fp_line
			(start -0.7874 0.4064)
			(end -0.7874 -0.4064)
			(stroke
				(width 0.1524)
				(type default)
			)
			(layer "F.SilkS")
		)
		(fp_line
			(start 0.7874 0.4064)
			(end -0.7874 0.4064)
			(stroke
				(width 0.1524)
				(type default)
			)
			(layer "F.SilkS")
		)
		(fp_line
			(start 0 0.381)
			(end 0 -0.381)
			(stroke
				(width 0.1524)
				(type default)
			)
			(layer "F.SilkS")
		)
		(fp_line
			(start -0.7874 -0.4064)
			(end 0.7874 -0.4064)
			(stroke
				(width 0.1524)
				(type default)
			)
			(layer "F.SilkS")
		)
		(fp_line
			(start 0.7874 -0.4064)
			(end 0.7874 0.4064)
			(stroke
				(width 0.1524)
				(type default)
			)
			(layer "F.SilkS")
		)
		(fp_poly
			(pts
				(xy -0.5334 0.254) (xy -0.635 0.254) (xy -0.635 0.2286) (xy -0.635 -0.254) (xy -0.5334 -0.254) (xy -0.5334 -0.2794)
				(xy 0.5334 -0.2794) (xy 0.5334 -0.254) (xy 0.635 -0.254) (xy 0.635 0.254) (xy 0.5334 0.254) (xy 0.5334 0.2794)
				(xy -0.508 0.2794) (xy -0.5334 0.2794)
			)
			(stroke
				(width 0)
				(type default)
			)
			(fill no)
			(layer "F.CrtYd")
		)
		(pad "1" smd rect
			(at 0.40005 0 270)
			(size 0.4572 0.508)
			(layers "F.Cu" "F.Mask" "F.Paste")
			(net "P12V")
		)
		(pad "2" smd rect
			(at -0.40005 0 270)
			(size 0.4572 0.508)
			(layers "F.Cu" "F.Mask" "F.Paste")
			(net "GND")
		)
	)
	(footprint ""
		(layer "F.Cu")
		(at 72.157844 -415.986722 -90)
		(property "Reference" "C64"
			(at -3.59029 -0.092202 90)
			(unlocked yes)
			(layer "F.SilkS")
			(effects
				(font
					(size 0.7874 0.5842)
					(thickness 0.1524)
				)
			)
		)
		(property "Value" ""
			(at 0 0 270)
			(layer "F.Fab")
			(effects
				(font
					(size 1.27 1.27)
				)
			)
		)
		(duplicate_pad_numbers_are_jumpers no)
		(fp_line
			(start -1.2954 0.5842)
			(end -1.2954 -0.5842)
			(stroke
				(width 0.1524)
				(type default)
			)
			(layer "F.SilkS")
		)
		(fp_line
			(start 1.2954 0.5842)
			(end -1.2954 0.5842)
			(stroke
				(width 0.1524)
				(type default)
			)
			(layer "F.SilkS")
		)
		(fp_line
			(start -1.2954 -0.5842)
			(end 1.2954 -0.5842)
			(stroke
				(width 0.1524)
				(type default)
			)
			(layer "F.SilkS")
		)
		(fp_line
			(start 0 -0.5842)
			(end 0 0.5842)
			(stroke
				(width 0.1524)
				(type default)
			)
			(layer "F.SilkS")
		)
		(fp_line
			(start 1.2954 -0.5842)
			(end 1.2954 0.5842)
			(stroke
				(width 0.1524)
				(type default)
			)
			(layer "F.SilkS")
		)
		(fp_poly
			(pts
				(xy 0.8636 -0.4572) (xy 0.8636 -0.3556) (xy 1.143 -0.3556) (xy 1.143 0.3556) (xy 0.8636 0.3556)
				(xy 0.8636 0.4572) (xy -0.8636 0.4572) (xy -0.8636 0.3556) (xy -1.143 0.3556) (xy -1.143 -0.3556)
				(xy -0.8636 -0.3556) (xy -0.8636 -0.4572)
			)
			(stroke
				(width 0)
				(type default)
			)
			(fill no)
			(layer "F.CrtYd")
		)
		(fp_line
			(start -0.884936 0.504952)
			(end -0.884936 -0.504952)
			(stroke
				(width 0.1)
				(type default)
			)
			(layer "F.Fab")
		)
		(fp_line
			(start 0.884936 0.504952)
			(end -0.884936 0.504952)
			(stroke
				(width 0.1)
				(type default)
			)
			(layer "F.Fab")
		)
		(fp_line
			(start -0.884936 -0.504952)
			(end 0.884936 -0.504952)
			(stroke
				(width 0.1)
				(type default)
			)
			(layer "F.Fab")
		)
		(fp_line
			(start 0.884936 -0.504952)
			(end 0.884936 0.504952)
			(stroke
				(width 0.1)
				(type default)
			)
			(layer "F.Fab")
		)
		(pad "1" smd rect
			(at 0.7366 0)
			(size 0.7112 0.8128)
			(layers "F.Cu" "F.Mask" "F.Paste")
			(net "P12V")
		)
		(pad "2" smd rect
			(at -0.7366 0)
			(size 0.7112 0.8128)
			(layers "F.Cu" "F.Mask" "F.Paste")
			(net "GND")
		)
	)
	(footprint ""
		(layer "F.Cu")
		(at 72.953626 -472.101672 180)
		(property "Reference" "R132"
			(at 1.12141 -1.136904 0)
			(unlocked yes)
			(layer "F.SilkS")
			(effects
				(font
					(size 0.7874 0.5842)
					(thickness 0.1524)
				)
				(justify left)
			)
		)
		(property "Value" ""
			(at 0 0 180)
			(layer "F.Fab")
			(effects
				(font
					(size 1.27 1.27)
				)
			)
		)
		(duplicate_pad_numbers_are_jumpers no)
		(fp_line
			(start 0.7874 0.4064)
			(end -0.7874 0.4064)
			(stroke
				(width 0.1524)
				(type default)
			)
			(layer "F.SilkS")
		)
		(fp_line
			(start 0.7874 -0.4064)
			(end 0.7874 0.4064)
			(stroke
				(width 0.1524)
				(type default)
			)
			(layer "F.SilkS")
		)
		(fp_line
			(start -0.7874 0.4064)
			(end -0.7874 -0.4064)
			(stroke
				(width 0.1524)
				(type default)
			)
			(layer "F.SilkS")
		)
		(fp_line
			(start -0.7874 -0.4064)
			(end 0.7874 -0.4064)
			(stroke
				(width 0.1524)
				(type default)
			)
			(layer "F.SilkS")
		)
		(fp_poly
			(pts
				(xy -0.508 0.2794) (xy -0.508 0.2286) (xy -0.635 0.2286) (xy -0.635 -0.254) (xy -0.5334 -0.254)
				(xy -0.5334 -0.2794) (xy 0.5334 -0.2794) (xy 0.5334 -0.254) (xy 0.635 -0.254) (xy 0.635 0.254) (xy 0.5334 0.254)
				(xy 0.5334 0.2794)
			)
			(stroke
				(width 0)
				(type default)
			)
			(fill no)
			(layer "F.CrtYd")
		)
		(pad "1" smd rect
			(at 0.40005 0 180)
			(size 0.4572 0.508)
			(layers "F.Cu" "F.Mask" "F.Paste")
			(net "PSU6_REMOTE_R2_N")
		)
		(pad "2" smd rect
			(at -0.40005 0 180)
			(size 0.4572 0.508)
			(layers "F.Cu" "F.Mask" "F.Paste")
			(net "GND")
		)
	)
)
